# SCM (Grand Teton) — schematic netlist excerpt (pin names and nets, part order shuffled) for the footprints in the layout excerpt that follows; sources: Cadence DE-HDL packaged netlist, KiCad conversion of 12092022_DA0F0TMDCD0_F0T_Management_Board_D_brd_V3_OCP.brd

R222  Q_RES  33.2 1% CHIP  pkg 0402LF  page 32 : A = JTAG_1_BMC_TCK_R ; B = JTAG_MB_TCK

Q10  MOSFET_N_GSD  DMG6968U-7 IC  pkg SOT23_GDSXC  page 17
  DRAIN  = LPC_ESPI_SEL_N
  GATE  = LPC_ESPI_SEL_R
  SOURCE  = GND

(kicad_pcb
	(version 20260206)
	(generator "pcbnew")
	(generator_version "10.0")
	(general
		(thickness 1.6)
		(legacy_teardrops no)
	)
	(paper "A4")
	(title_block
		(title "12092022_DA0F0TMDCD0_F0T_Management_Board_D_brd_V3_OCP.brd")
		(comment 1 "Grand Teton / footprints 1380-1381 of 1440")
	)
	(layers
		(0 "F.Cu" signal "TOP")
		(4 "In1.Cu" signal "GND")
		(6 "In2.Cu" signal "IN1")
		(8 "In3.Cu" signal "GND1")
		(10 "In4.Cu" signal "IN2")
		(12 "In5.Cu" signal "VCC")
		(14 "In6.Cu" signal "VCC1")
		(16 "In7.Cu" signal "IN3")
		(18 "In8.Cu" signal "GND2")
		(20 "In9.Cu" signal "IN4")
		(22 "In10.Cu" signal "GND3")
		(2 "B.Cu" signal "BOTTOM")
		(9 "F.Adhes" user "F.Adhesive")
		(11 "B.Adhes" user "B.Adhesive")
		(13 "F.Paste" user "Package Geometry/Pastemask Top")
		(15 "B.Paste" user "Package Geometry/Pastemask Bottom")
		(5 "F.SilkS" user "Ref Des/Silkscreen Top")
		(7 "B.SilkS" user "Ref Des/Silkscreen Bottom")
		(1 "F.Mask" user "Board Geometry/Soldermask Top")
		(3 "B.Mask" user "Board Geometry/Soldermask Bottom")
		(17 "Dwgs.User" user "User.Drawings")
		(19 "Cmts.User" user "User.Comments")
		(21 "Eco1.User" user "User.Eco1")
		(23 "Eco2.User" user "User.Eco2")
		(25 "Edge.Cuts" user "Board Geometry/Outline")
		(27 "Margin" user)
		(31 "F.CrtYd" user "Package Geometry/Place Bound Top")
		(29 "B.CrtYd" user "Package Geometry/Place Bound Bottom")
		(35 "F.Fab" user "Ref Des/Assembly Top")
		(33 "B.Fab" user "Ref Des/Assembly Bottom")
	)
	(footprint ""
		(layer "B.Cu")
		(at 78.355444 -97.119186 90)
		(property "Reference" "Q10"
			(at -1.273556 3.877056 0)
			(unlocked yes)
			(layer "B.SilkS")
			(effects
				(font
					(size 0.7874 0.5842)
					(thickness 0.1524)
				)
				(justify left mirror)
			)
		)
		(property "Value" ""
			(at 0 0 90)
			(layer "B.Fab")
			(effects
				(font
					(size 1.27 1.27)
				)
				(justify mirror)
			)
		)
		(duplicate_pad_numbers_are_jumpers no)
		(fp_line
			(start 1.603248 -1.500124)
			(end -1.603248 -1.500124)
			(stroke
				(width 0.1524)
				(type default)
			)
			(layer "B.SilkS")
		)
		(fp_line
			(start -1.603248 -1.500124)
			(end -1.603248 1.500124)
			(stroke
				(width 0.1524)
				(type default)
			)
			(layer "B.SilkS")
		)
		(fp_line
			(start 1.603248 1.500124)
			(end 1.603248 -1.500124)
			(stroke
				(width 0.1524)
				(type default)
			)
			(layer "B.SilkS")
		)
		(fp_line
			(start -1.603248 1.500124)
			(end 1.603248 1.500124)
			(stroke
				(width 0.1524)
				(type default)
			)
			(layer "B.SilkS")
		)
		(fp_line
			(start 0.700024 -1.500124)
			(end 0.700024 -1.169924)
			(stroke
				(width 0.1)
				(type default)
			)
			(layer "B.Fab")
		)
		(fp_line
			(start -0.700024 -1.500124)
			(end 0.700024 -1.500124)
			(stroke
				(width 0.1)
				(type default)
			)
			(layer "B.Fab")
		)
		(fp_line
			(start 1.249934 -1.169924)
			(end 1.249934 -0.729996)
			(stroke
				(width 0.1)
				(type default)
			)
			(layer "B.Fab")
		)
		(fp_line
			(start 0.700024 -1.169924)
			(end 1.249934 -1.169924)
			(stroke
				(width 0.1)
				(type default)
			)
			(layer "B.Fab")
		)
		(fp_line
			(start 1.249934 -0.729996)
			(end 0.6985 -0.729996)
			(stroke
				(width 0.1)
				(type default)
			)
			(layer "B.Fab")
		)
		(fp_line
			(start 0.6985 -0.729996)
			(end 0.6985 0.729996)
			(stroke
				(width 0.1)
				(type default)
			)
			(layer "B.Fab")
		)
		(fp_line
			(start -0.700024 -0.219964)
			(end -0.700024 -1.500124)
			(stroke
				(width 0.1)
				(type default)
			)
			(layer "B.Fab")
		)
		(fp_line
			(start -1.249934 -0.219964)
			(end -0.700024 -0.219964)
			(stroke
				(width 0.1)
				(type default)
			)
			(layer "B.Fab")
		)
		(fp_line
			(start -0.700024 0.219964)
			(end -1.249934 0.219964)
			(stroke
				(width 0.1)
				(type default)
			)
			(layer "B.Fab")
		)
		(fp_line
			(start -1.249934 0.219964)
			(end -1.249934 -0.219964)
			(stroke
				(width 0.1)
				(type default)
			)
			(layer "B.Fab")
		)
		(fp_line
			(start 1.249934 0.729996)
			(end 1.249934 1.169924)
			(stroke
				(width 0.1)
				(type default)
			)
			(layer "B.Fab")
		)
		(fp_line
			(start 0.6985 0.729996)
			(end 1.249934 0.729996)
			(stroke
				(width 0.1)
				(type default)
			)
			(layer "B.Fab")
		)
		(fp_line
			(start 1.249934 1.169924)
			(end 0.700024 1.169924)
			(stroke
				(width 0.1)
				(type default)
			)
			(layer "B.Fab")
		)
		(fp_line
			(start 0.700024 1.169924)
			(end 0.700024 1.500124)
			(stroke
				(width 0.1)
				(type default)
			)
			(layer "B.Fab")
		)
		(fp_line
			(start 0.700024 1.500124)
			(end -0.700024 1.500124)
			(stroke
				(width 0.1)
				(type default)
			)
			(layer "B.Fab")
		)
		(fp_line
			(start -0.700024 1.500124)
			(end -0.700024 0.219964)
			(stroke
				(width 0.1)
				(type default)
			)
			(layer "B.Fab")
		)
		(fp_rect
			(start 0.700024 1.500124)
			(end -0.700024 -1.500124)
			(stroke
				(width 0)
				(type default)
			)
			(fill no)
			(layer "B.Fab")
		)
		(pad "D" smd rect
			(at -0.999998 0)
			(size 0.8128 0.9144)
			(layers "B.Cu" "B.Mask" "B.Paste")
			(net "LPC_ESPI_SEL_N")
		)
		(pad "G" smd rect
			(at 0.999998 -0.94996)
			(size 0.8128 0.9144)
			(layers "B.Cu" "B.Mask" "B.Paste")
			(net "LPC_ESPI_SEL_R")
		)
		(pad "S" smd rect
			(at 0.999998 0.94996)
			(size 0.8128 0.9144)
			(layers "B.Cu" "B.Mask" "B.Paste")
			(net "GND")
		)
	)
	(footprint ""
		(layer "B.Cu")
		(at 46.470316 -34.637726 90)
		(property "Reference" "R222"
			(at 0 0 90)
			(layer "B.SilkS")
			(hide yes)
			(effects
				(font
					(size 1.27 1.27)
				)
				(justify mirror)
			)
		)
		(property "Value" ""
			(at 0 0 90)
			(layer "B.Fab")
			(effects
				(font
					(size 1.27 1.27)
				)
				(justify mirror)
			)
		)
		(duplicate_pad_numbers_are_jumpers no)
		(fp_line
			(start 0.7874 -0.4064)
			(end -0.7874 -0.4064)
			(stroke
				(width 0.1524)
				(type default)
			)
			(layer "B.SilkS")
		)
		(fp_line
			(start -0.7874 -0.4064)
			(end -0.7874 0.4064)
			(stroke
				(width 0.1524)
				(type default)
			)
			(layer "B.SilkS")
		)
		(fp_line
			(start 0.7874 0.4064)
			(end 0.7874 -0.4064)
			(stroke
				(width 0.1524)
				(type default)
			)
			(layer "B.SilkS")
		)
		(fp_line
			(start -0.7874 0.4064)
			(end 0.7874 0.4064)
			(stroke
				(width 0.1524)
				(type default)
			)
			(layer "B.SilkS")
		)
		(fp_line
			(start 0.67945 -0.305054)
			(end 0.12065 -0.305054)
			(stroke
				(width 0.1)
				(type default)
			)
			(layer "B.Fab")
		)
		(fp_line
			(start 0.12065 -0.305054)
			(end 0.12065 -0.2794)
			(stroke
				(width 0.1)
				(type default)
			)
			(layer "B.Fab")
		)
		(fp_line
			(start -0.12065 -0.3048)
			(end -0.67945 -0.3048)
			(stroke
				(width 0.1)
				(type default)
			)
			(layer "B.Fab")
		)
		(fp_line
			(start -0.67945 -0.3048)
			(end -0.67945 0.3048)
			(stroke
				(width 0.1)
				(type default)
			)
			(layer "B.Fab")
		)
		(fp_line
			(start 0.12065 -0.2794)
			(end -0.12065 -0.2794)
			(stroke
				(width 0.1)
				(type default)
			)
			(layer "B.Fab")
		)
		(fp_line
			(start -0.12065 -0.2794)
			(end -0.12065 -0.3048)
			(stroke
				(width 0.1)
				(type default)
			)
			(layer "B.Fab")
		)
		(fp_line
			(start 0.12065 0.2794)
			(end 0.12065 0.3048)
			(stroke
				(width 0.1)
				(type default)
			)
			(layer "B.Fab")
		)
		(fp_line
			(start -0.120396 0.2794)
			(end 0.12065 0.2794)
			(stroke
				(width 0.1)
				(type default)
			)
			(layer "B.Fab")
		)
		(fp_line
			(start 0.67945 0.3048)
			(end 0.67945 -0.305054)
			(stroke
				(width 0.1)
				(type default)
			)
			(layer "B.Fab")
		)
		(fp_line
			(start 0.12065 0.3048)
			(end 0.67945 0.3048)
			(stroke
				(width 0.1)
				(type default)
			)
			(layer "B.Fab")
		)
		(fp_line
			(start -0.120396 0.3048)
			(end -0.120396 0.2794)
			(stroke
				(width 0.1)
				(type default)
			)
			(layer "B.Fab")
		)
		(fp_line
			(start -0.67945 0.3048)
			(end -0.120396 0.3048)
			(stroke
				(width 0.1)
				(type default)
			)
			(layer "B.Fab")
		)
		(pad "1" smd circle
			(at 0.40005 0 270)
			(size 0 0)
			(layers "B.Cu" "B.Mask" "B.Paste")
			(net "JTAG_1_BMC_TCK_R")
		)
		(pad "2" smd circle
			(at -0.40005 0 270)
			(size 0 0)
			(layers "B.Cu" "B.Mask" "B.Paste")
			(net "JTAG_MB_TCK")
		)
	)
)
